(kicad_pcb
	(version 20260206)
	(generator "pcbnew")
	(generator_version "10.0")
	(general
		(thickness 1.6)
		(legacy_teardrops no)
	)
	(paper "A4")
	(title_block
		(title "peb — Lightning_PEB_BRD.brd")
		(comment 1 "Lightning (Wiwynn / Facebook NVMe JBOF) / footprints 1369-1374 of 2563")
	)
	(layers
		(0 "F.Cu" signal "TOP")
		(4 "In1.Cu" signal "L2GND")
		(6 "In2.Cu" signal "L3")
		(8 "In3.Cu" signal "L4VCC")
		(10 "In4.Cu" signal "L5VCC")
		(12 "In5.Cu" signal "L6")
		(14 "In6.Cu" signal "L7GND")
		(2 "B.Cu" signal "BOTTOM")
		(9 "F.Adhes" user "F.Adhesive")
		(11 "B.Adhes" user "B.Adhesive")
		(13 "F.Paste" user "Package Geometry/Pastemask Top")
		(15 "B.Paste" user "Package Geometry/Pastemask Bottom")
		(5 "F.SilkS" user "Ref Des/Silkscreen Top")
		(7 "B.SilkS" user "Ref Des/Silkscreen Bottom")
		(1 "F.Mask" user "Board Geometry/Soldermask Top")
		(3 "B.Mask" user "Board Geometry/Soldermask Bottom")
		(17 "Dwgs.User" user "User.Drawings")
		(19 "Cmts.User" user "User.Comments")
		(21 "Eco1.User" user "User.Eco1")
		(23 "Eco2.User" user "User.Eco2")
		(25 "Edge.Cuts" user "Board Geometry/Outline")
		(27 "Margin" user)
		(31 "F.CrtYd" user "Package Geometry/Place Bound Top")
		(29 "B.CrtYd" user "Package Geometry/Place Bound Bottom")
		(35 "F.Fab" user "Ref Des/Assembly Top")
		(33 "B.Fab" user "Ref Des/Assembly Bottom")
	)
	(footprint ""
		(layer "F.Cu")
		(at 297.8658 -206.8068 -90)
		(property "Reference" "C4132"
			(at 0 0 270)
			(layer "F.SilkS")
			(hide yes)
			(effects
				(font
					(size 1.27 1.27)
				)
			)
		)
		(property "Value" "SCD1U25V3KX-GP"
			(at 0 -2.8194 270)
			(unlocked yes)
			(layer "F.Fab")
			(hide yes)
			(effects
				(font
					(size 1.016 1.016)
					(thickness 0.1524)
				)
			)
		)
		(property "Device Type" "C603H36"
			(at 0 -4.3434 270)
			(unlocked yes)
			(layer "F.Fab")
			(hide yes)
			(effects
				(font
					(size 1.016 1.016)
					(thickness 0.1524)
				)
			)
		)
		(duplicate_pad_numbers_are_jumpers no)
		(fp_line
			(start 0.508 0)
			(end -0.508 0)
			(stroke
				(width 0.2032)
				(type default)
			)
			(layer "F.SilkS")
		)
		(fp_rect
			(start -0.5842 1.3335)
			(end 0.5842 -1.3335)
			(stroke
				(width 0)
				(type default)
			)
			(fill no)
			(layer "F.CrtYd")
		)
		(fp_rect
			(start -0.5842 1.3335)
			(end 0.5842 -1.3335)
			(stroke
				(width 0)
				(type default)
			)
			(fill no)
			(layer "F.Fab")
		)
		(pad "1" smd custom
			(at 0 -0.762 270)
			(size 0.2159 0.2159)
			(layers "F.Cu" "F.Mask" "F.Paste")
			(net "GND")
			(options
				(clearance outline)
				(anchor circle)
			)
			(primitives
				(gr_poly
					(pts
						(arc
							(start -0.3302 -0.4318)
							(mid -0.402042 -0.402042)
							(end -0.4318 -0.3302)
						)
						(arc
							(start -0.4318 0.3302)
							(mid -0.402042 0.402042)
							(end -0.3302 0.4318)
						)
						(arc
							(start 0.3302 0.4318)
							(mid 0.402042 0.402042)
							(end 0.4318 0.3302)
						)
						(arc
							(start 0.4318 -0.3302)
							(mid 0.402042 -0.402042)
							(end 0.3302 -0.4318)
						)
					)
					(width 0)
					(fill yes)
				)
			)
		)
		(pad "2" smd custom
			(at 0 0.762 270)
			(size 0.2159 0.2159)
			(layers "F.Cu" "F.Mask" "F.Paste")
			(net "SSD_PWREN13_R")
			(options
				(clearance outline)
				(anchor circle)
			)
			(primitives
				(gr_poly
					(pts
						(arc
							(start -0.3302 -0.4318)
							(mid -0.402042 -0.402042)
							(end -0.4318 -0.3302)
						)
						(arc
							(start -0.4318 0.3302)
							(mid -0.402042 0.402042)
							(end -0.3302 0.4318)
						)
						(arc
							(start 0.3302 0.4318)
							(mid 0.402042 0.402042)
							(end 0.4318 0.3302)
						)
						(arc
							(start 0.4318 -0.3302)
							(mid 0.402042 -0.402042)
							(end 0.3302 -0.4318)
						)
					)
					(width 0)
					(fill yes)
				)
			)
		)
	)
	(footprint ""
		(layer "F.Cu")
		(at 70.6374 -120.9802 180)
		(property "Reference" "R22"
			(at 0 0 180)
			(layer "F.SilkS")
			(hide yes)
			(effects
				(font
					(size 1.27 1.27)
				)
			)
		)
		(property "Value" "0R2J-2-GP"
			(at 0.064008 -3.993896 180)
			(unlocked yes)
			(layer "F.Fab")
			(hide yes)
			(effects
				(font
					(size 1.016 1.016)
					(thickness 0.1524)
				)
			)
		)
		(property "Device Type" "R402H16"
			(at 0.064008 -5.517896 180)
			(unlocked yes)
			(layer "F.Fab")
			(hide yes)
			(effects
				(font
					(size 1.016 1.016)
					(thickness 0.1524)
				)
			)
		)
		(duplicate_pad_numbers_are_jumpers no)
		(fp_line
			(start 0.508 -0.9398)
			(end -0.508 -0.9398)
			(stroke
				(width 0.1524)
				(type default)
			)
			(layer "F.SilkS")
		)
		(fp_line
			(start -0.508 -0.9398)
			(end -0.508 0.9398)
			(stroke
				(width 0.1524)
				(type default)
			)
			(layer "F.SilkS")
		)
		(fp_rect
			(start -0.508 0.9398)
			(end 0.508 -0.9398)
			(stroke
				(width 0)
				(type default)
			)
			(fill no)
			(layer "F.CrtYd")
		)
		(fp_rect
			(start -0.508 0.9398)
			(end 0.508 -0.9398)
			(stroke
				(width 0)
				(type default)
			)
			(fill no)
			(layer "F.Fab")
		)
		(pad "1" smd custom
			(at 0 -0.4445 180)
			(size 0.1397 0.1397)
			(layers "F.Cu" "F.Mask" "F.Paste")
			(net "BMC_I2C4_MINI4_SDA")
			(options
				(clearance outline)
				(anchor circle)
			)
			(primitives
				(gr_poly
					(pts
						(arc
							(start -0.1778 -0.2794)
							(mid -0.249642 -0.249642)
							(end -0.2794 -0.1778)
						)
						(arc
							(start -0.2794 0.1778)
							(mid -0.249642 0.249642)
							(end -0.1778 0.2794)
						)
						(arc
							(start 0.1778 0.2794)
							(mid 0.249642 0.249642)
							(end 0.2794 0.1778)
						)
						(arc
							(start 0.2794 -0.1778)
							(mid 0.249642 -0.249642)
							(end 0.1778 -0.2794)
						)
					)
					(width 0)
					(fill yes)
				)
			)
		)
		(pad "2" smd custom
			(at 0 0.4445 180)
			(size 0.1397 0.1397)
			(layers "F.Cu" "F.Mask" "F.Paste")
			(net "BMC_I2C4_MINI4_SDA_S")
			(options
				(clearance outline)
				(anchor circle)
			)
			(primitives
				(gr_poly
					(pts
						(arc
							(start -0.1778 -0.2794)
							(mid -0.249642 -0.249642)
							(end -0.2794 -0.1778)
						)
						(arc
							(start -0.2794 0.1778)
							(mid -0.249642 0.249642)
							(end -0.1778 0.2794)
						)
						(arc
							(start 0.1778 0.2794)
							(mid 0.249642 0.249642)
							(end 0.2794 0.1778)
						)
						(arc
							(start 0.2794 -0.1778)
							(mid 0.249642 -0.249642)
							(end 0.1778 -0.2794)
						)
					)
					(width 0)
					(fill yes)
				)
			)
		)
	)
	(footprint ""
		(layer "F.Cu")
		(at 85.4964 -85.217 -90)
		(property "Reference" "SR949"
			(at 0 0 270)
			(layer "F.SilkS")
			(hide yes)
			(effects
				(font
					(size 1.27 1.27)
				)
			)
		)
		(property "Value" "0R2J-2-GP"
			(at 0.064008 -3.993896 270)
			(unlocked yes)
			(layer "F.Fab")
			(hide yes)
			(effects
				(font
					(size 1.016 1.016)
					(thickness 0.1524)
				)
			)
		)
		(property "Device Type" "R402H16"
			(at 0.064008 -5.517896 270)
			(unlocked yes)
			(layer "F.Fab")
			(hide yes)
			(effects
				(font
					(size 1.016 1.016)
					(thickness 0.1524)
				)
			)
		)
		(duplicate_pad_numbers_are_jumpers no)
		(fp_line
			(start -0.508 -0.9398)
			(end -0.508 0.9398)
			(stroke
				(width 0.1524)
				(type default)
			)
			(layer "F.SilkS")
		)
		(fp_line
			(start 0.508 -0.9398)
			(end -0.508 -0.9398)
			(stroke
				(width 0.1524)
				(type default)
			)
			(layer "F.SilkS")
		)
		(fp_rect
			(start -0.508 0.9398)
			(end 0.508 -0.9398)
			(stroke
				(width 0)
				(type default)
			)
			(fill no)
			(layer "F.CrtYd")
		)
		(fp_rect
			(start -0.508 0.9398)
			(end 0.508 -0.9398)
			(stroke
				(width 0)
				(type default)
			)
			(fill no)
			(layer "F.Fab")
		)
		(pad "1" smd custom
			(at 0 -0.4445 270)
			(size 0.1397 0.1397)
			(layers "F.Cu" "F.Mask" "F.Paste")
			(net "EXP_SMART_RX")
			(options
				(clearance outline)
				(anchor circle)
			)
			(primitives
				(gr_poly
					(pts
						(arc
							(start -0.1778 -0.2794)
							(mid -0.249642 -0.249642)
							(end -0.2794 -0.1778)
						)
						(arc
							(start -0.2794 0.1778)
							(mid -0.249642 0.249642)
							(end -0.1778 0.2794)
						)
						(arc
							(start 0.1778 0.2794)
							(mid 0.249642 0.249642)
							(end 0.2794 0.1778)
						)
						(arc
							(start 0.2794 -0.1778)
							(mid 0.249642 -0.249642)
							(end 0.1778 -0.2794)
						)
					)
					(width 0)
					(fill yes)
				)
			)
		)
		(pad "2" smd custom
			(at 0 0.4445 270)
			(size 0.1397 0.1397)
			(layers "F.Cu" "F.Mask" "F.Paste")
			(net "EXP_SMART_RX_R")
			(options
				(clearance outline)
				(anchor circle)
			)
			(primitives
				(gr_poly
					(pts
						(arc
							(start -0.1778 -0.2794)
							(mid -0.249642 -0.249642)
							(end -0.2794 -0.1778)
						)
						(arc
							(start -0.2794 0.1778)
							(mid -0.249642 0.249642)
							(end -0.1778 0.2794)
						)
						(arc
							(start 0.1778 0.2794)
							(mid 0.249642 0.249642)
							(end 0.2794 0.1778)
						)
						(arc
							(start 0.2794 -0.1778)
							(mid 0.249642 -0.249642)
							(end 0.1778 -0.2794)
						)
					)
					(width 0)
					(fill yes)
				)
			)
		)
	)
	(footprint ""
		(layer "F.Cu")
		(at 143.68526 -33.45942 180)
		(property "Reference" "R668"
			(at 0 0 180)
			(layer "F.SilkS")
			(hide yes)
			(effects
				(font
					(size 1.27 1.27)
				)
			)
		)
		(property "Value" "0R2J-2-GP"
			(at 0.064008 -3.993896 180)
			(unlocked yes)
			(layer "F.Fab")
			(hide yes)
			(effects
				(font
					(size 1.016 1.016)
					(thickness 0.1524)
				)
			)
		)
		(property "Device Type" "R402H16"
			(at 0.064008 -5.517896 180)
			(unlocked yes)
			(layer "F.Fab")
			(hide yes)
			(effects
				(font
					(size 1.016 1.016)
					(thickness 0.1524)
				)
			)
		)
		(duplicate_pad_numbers_are_jumpers no)
		(fp_line
			(start 0.508 -0.9398)
			(end -0.508 -0.9398)
			(stroke
				(width 0.1524)
				(type default)
			)
			(layer "F.SilkS")
		)
		(fp_line
			(start -0.508 -0.9398)
			(end -0.508 0.9398)
			(stroke
				(width 0.1524)
				(type default)
			)
			(layer "F.SilkS")
		)
		(fp_rect
			(start -0.508 0.9398)
			(end 0.508 -0.9398)
			(stroke
				(width 0)
				(type default)
			)
			(fill no)
			(layer "F.CrtYd")
		)
		(fp_rect
			(start -0.508 0.9398)
			(end 0.508 -0.9398)
			(stroke
				(width 0)
				(type default)
			)
			(fill no)
			(layer "F.Fab")
		)
		(pad "1" smd custom
			(at 0 -0.4445 180)
			(size 0.1397 0.1397)
			(layers "F.Cu" "F.Mask" "F.Paste")
			(net "8644_USB_DN2")
			(options
				(clearance outline)
				(anchor circle)
			)
			(primitives
				(gr_poly
					(pts
						(arc
							(start -0.1778 -0.2794)
							(mid -0.249642 -0.249642)
							(end -0.2794 -0.1778)
						)
						(arc
							(start -0.2794 0.1778)
							(mid -0.249642 0.249642)
							(end -0.1778 0.2794)
						)
						(arc
							(start 0.1778 0.2794)
							(mid 0.249642 0.249642)
							(end 0.2794 0.1778)
						)
						(arc
							(start 0.2794 -0.1778)
							(mid 0.249642 -0.249642)
							(end 0.1778 -0.2794)
						)
					)
					(width 0)
					(fill yes)
				)
			)
		)
		(pad "2" smd custom
			(at 0 0.4445 180)
			(size 0.1397 0.1397)
			(layers "F.Cu" "F.Mask" "F.Paste")
			(net "P3V3_STBY")
			(options
				(clearance outline)
				(anchor circle)
			)
			(primitives
				(gr_poly
					(pts
						(arc
							(start -0.1778 -0.2794)
							(mid -0.249642 -0.249642)
							(end -0.2794 -0.1778)
						)
						(arc
							(start -0.2794 0.1778)
							(mid -0.249642 0.249642)
							(end -0.1778 0.2794)
						)
						(arc
							(start 0.1778 0.2794)
							(mid 0.249642 0.249642)
							(end 0.2794 0.1778)
						)
						(arc
							(start 0.2794 -0.1778)
							(mid 0.249642 -0.249642)
							(end 0.1778 -0.2794)
						)
					)
					(width 0)
					(fill yes)
				)
			)
		)
	)
	(footprint ""
		(layer "F.Cu")
		(at 305.816 -57.0992)
		(property "Reference" "C431"
			(at 0 0 0)
			(layer "F.SilkS")
			(hide yes)
			(effects
				(font
					(size 1.27 1.27)
				)
			)
		)
		(property "Value" "SC10U16V5KX-1-GP"
			(at -0.0762 -6.1214 0)
			(unlocked yes)
			(layer "F.Fab")
			(hide yes)
			(effects
				(font
					(size 1.016 1.016)
					(thickness 0.1524)
				)
			)
		)
		(property "Device Type" "C805H54"
			(at -0.0762 -8.1534 0)
			(unlocked yes)
			(layer "F.Fab")
			(hide yes)
			(effects
				(font
					(size 1.016 1.016)
					(thickness 0.1524)
				)
			)
		)
		(duplicate_pad_numbers_are_jumpers no)
		(fp_line
			(start 0.635 0)
			(end -0.635 0)
			(stroke
				(width 0.508)
				(type default)
			)
			(layer "F.SilkS")
		)
		(fp_rect
			(start -0.9652 1.778)
			(end 0.9652 -1.778)
			(stroke
				(width 0)
				(type default)
			)
			(fill no)
			(layer "F.CrtYd")
		)
		(fp_poly
			(pts
				(xy -0.9652 -1.778) (xy 0.9652 -1.778) (xy 0.9652 1.778) (xy -0.9652 1.778)
			)
			(stroke
				(width 0)
				(type default)
			)
			(fill no)
			(layer "F.Fab")
		)
		(pad "1" smd rect
			(at 0 -0.9652)
			(size 1.397 1.143)
			(layers "F.Cu" "F.Mask" "F.Paste")
			(net "DUT_VDD")
		)
		(pad "2" smd rect
			(at 0 0.9652)
			(size 1.397 1.143)
			(layers "F.Cu" "F.Mask" "F.Paste")
			(net "GND")
		)
	)
	(footprint ""
		(layer "F.Cu")
		(at 9.5758 -175.387)
		(property "Reference" "R738"
			(at 0 0 0)
			(layer "F.SilkS")
			(hide yes)
			(effects
				(font
					(size 1.27 1.27)
				)
			)
		)
		(property "Value" "10KR3F-L-GP"
			(at -0.0254 -2.5146 0)
			(unlocked yes)
			(layer "F.Fab")
			(hide yes)
			(effects
				(font
					(size 1.016 1.016)
					(thickness 0.1524)
				)
			)
		)
		(property "Device Type" "R603H22"
			(at -0.0254 -4.0386 0)
			(unlocked yes)
			(layer "F.Fab")
			(hide yes)
			(effects
				(font
					(size 1.016 1.016)
					(thickness 0.1524)
				)
			)
		)
		(duplicate_pad_numbers_are_jumpers no)
		(fp_line
			(start -0.4826 0)
			(end -0.2032 0)
			(stroke
				(width 0.2032)
				(type default)
			)
			(layer "F.SilkS")
		)
		(fp_line
			(start 0.2032 0)
			(end 0.4826 0)
			(stroke
				(width 0.2032)
				(type default)
			)
			(layer "F.SilkS")
		)
		(fp_rect
			(start -0.5842 1.3335)
			(end 0.5842 -1.3335)
			(stroke
				(width 0)
				(type default)
			)
			(fill no)
			(layer "F.CrtYd")
		)
		(fp_rect
			(start -0.5842 1.3335)
			(end 0.5842 -1.3335)
			(stroke
				(width 0)
				(type default)
			)
			(fill no)
			(layer "F.Fab")
		)
		(pad "1" smd custom
			(at 0 -0.762)
			(size 0.2159 0.2159)
			(layers "F.Cu" "F.Mask" "F.Paste")
			(net "P12V_PCIE")
			(options
				(clearance outline)
				(anchor circle)
			)
			(primitives
				(gr_poly
					(pts
						(arc
							(start -0.3302 -0.4318)
							(mid -0.402042 -0.402042)
							(end -0.4318 -0.3302)
						)
						(arc
							(start -0.4318 0.3302)
							(mid -0.402042 0.402042)
							(end -0.3302 0.4318)
						)
						(arc
							(start 0.3302 0.4318)
							(mid 0.402042 0.402042)
							(end 0.4318 0.3302)
						)
						(arc
							(start 0.4318 -0.3302)
							(mid 0.402042 -0.402042)
							(end 0.3302 -0.4318)
						)
					)
					(width 0)
					(fill yes)
				)
			)
		)
		(pad "2" smd custom
			(at 0 0.762)
			(size 0.2159 0.2159)
			(layers "F.Cu" "F.Mask" "F.Paste")
			(net "Q95_G")
			(options
				(clearance outline)
				(anchor circle)
			)
			(primitives
				(gr_poly
					(pts
						(arc
							(start -0.3302 -0.4318)
							(mid -0.402042 -0.402042)
							(end -0.4318 -0.3302)
						)
						(arc
							(start -0.4318 0.3302)
							(mid -0.402042 0.402042)
							(end -0.3302 0.4318)
						)
						(arc
							(start 0.3302 0.4318)
							(mid 0.402042 0.402042)
							(end 0.4318 0.3302)
						)
						(arc
							(start 0.4318 -0.3302)
							(mid 0.402042 -0.402042)
							(end 0.3302 -0.4318)
						)
					)
					(width 0)
					(fill yes)
				)
			)
		)
	)
)
